(kicad_pcb
	(version 20221018)
	(generator pcbnew)
	(general
    (thickness 1.586)
  )
	(paper "A4")
	(title_block
    (date "2024-03-26")
    (rev "1.1.3")
		(comment 9 "footprints 131-138 of 146")
	)
	(layers
    (0 "F.Cu" signal)
    (1 "In1.Cu" power)
    (2 "In2.Cu" power)
    (31 "B.Cu" signal)
    (32 "B.Adhes" user "B.Adhesive")
    (33 "F.Adhes" user "F.Adhesive")
    (34 "B.Paste" user)
    (35 "F.Paste" user)
    (36 "B.SilkS" user "B.Silkscreen")
    (37 "F.SilkS" user "F.Silkscreen")
    (38 "B.Mask" user)
    (39 "F.Mask" user)
    (40 "Dwgs.User" user "User.Drawings")
    (41 "Cmts.User" user "User.Comments")
    (42 "Eco1.User" user "User.Eco1")
    (43 "Eco2.User" user "User.Eco2")
    (44 "Edge.Cuts" user)
    (45 "Margin" user)
    (46 "B.CrtYd" user "B.Courtyard")
    (47 "F.CrtYd" user "F.Courtyard")
    (48 "B.Fab" user)
    (49 "F.Fab" user)
  )
	(footprint "scalenode-cm4-baseboard-footprints:DO-214AC" (layer "B.Cu")
    (at 127 94.796 180)
    (property "Author" "Antmicro")
    (property "License" "Apache-2.0")
    (property "MPN" "SMAJ6.5A")
    (property "Manufacturer" "YAGEO")
    (property "Sheetfile" "poe.kicad_sch")
    (property "Sheetname" "PoE")
    (attr smd)
    (fp_text reference "D8" (at 3.425 0.596 90) (layer "B.SilkS")
        (effects (font (size 0.7 0.7) (thickness 0.15)) (justify left bottom mirror))
    )
    (fp_text value "SMAJ6.5A" (at -0.025 -0.029) (layer "B.Fab")
        (effects (font (size 0.7 0.7) (thickness 0.15)) (justify left bottom mirror))
    )
    (fp_text user "${REFERENCE}" (at -3.301 -4.45) (layer "B.Fab") hide
        (effects (font (size 0.7 0.7) (thickness 0.15)) (justify left bottom mirror))
    )
    (fp_text user "License: Apache-2.0" (at -3.301 -6.85) (layer "B.Fab") hide
        (effects (font (size 0.7 0.7) (thickness 0.15)) (justify left bottom mirror))
    )
    (fp_text user "Author: Antmicro" (at -3.301 -5.65) (layer "B.Fab") hide
        (effects (font (size 0.7 0.7) (thickness 0.15)) (justify left bottom mirror))
    )
    (fp_line (start -3.301 -1.5) (end 0 -1.5)
      (stroke (width 0.15) (type solid)) (layer "B.SilkS"))
    (fp_line (start -3.301 1.5) (end -3.301 -1.5)
      (stroke (width 0.15) (type solid)) (layer "B.SilkS"))
    (fp_line (start 0 1.5) (end -3.301 1.5)
      (stroke (width 0.15) (type solid)) (layer "B.SilkS"))
    (fp_rect (start -3.25 1.55) (end 3.25 -1.55)
      (stroke (width 0.05) (type solid)) (fill none) (layer "B.CrtYd"))
    (fp_line (start -2.15 -1.3) (end 2.148 -1.3)
      (stroke (width 0.15) (type solid)) (layer "B.Fab"))
    (fp_line (start -2.15 1.301) (end -2.15 -1.3)
      (stroke (width 0.15) (type solid)) (layer "B.Fab"))
    (fp_line (start -2.15 1.301) (end 2.148 1.301)
      (stroke (width 0.15) (type solid)) (layer "B.Fab"))
    (fp_line (start -1.442 -1.3) (end -1.365 -1.3)
      (stroke (width 0.15) (type solid)) (layer "B.Fab"))
    (fp_line (start -1.363 1.301) (end -1.442 1.301)
      (stroke (width 0.15) (type solid)) (layer "B.Fab"))
    (fp_line (start 2.148 1.301) (end 2.148 -1.3)
      (stroke (width 0.15) (type solid)) (layer "B.Fab"))
    (fp_rect (start -1.363 1.301) (end -1.1 -1.3)
      (stroke (width 0.15) (type solid)) (fill solid) (layer "B.Fab"))
    (pad "A" smd roundrect (at 1.999 0 180) (size 2 2.1) (layers "B.Cu" "B.Paste" "B.Mask") (roundrect_rratio 0.1)
      (net 11 "GND") (pinfunction "A") (pintype "passive"))
    (pad "K" smd roundrect (at -2 0 180) (size 2 2.1) (layers "B.Cu" "B.Paste" "B.Mask") (roundrect_rratio 0.1)
      (net 13 "/PoE/VO5V") (pinfunction "K") (pintype "passive"))
  )
	(footprint "scalenode-cm4-baseboard-footprints:C_2220_5650Metric" (layer "B.Cu")
    (at 113.550264 92.575272 -90)
    (descr "Capacitor SMD 2220")
    (tags "capacitor SMD 2220")
    (property "Author" "Antmicro")
    (property "Dielectric" "X7S")
    (property "License" "Apache-2.0")
    (property "MPN" "C5750X7S2A226M280KB")
    (property "Manufacturer" "TDK")
    (property "Sheetfile" "poe.kicad_sch")
    (property "Sheetname" "PoE")
    (property "Val" "22u")
    (property "Voltage" "100V")
    (property "ki_description" " ")
    (attr smd)
    (fp_text reference "C26" (at -4.085272 -1.039736 180) (layer "B.SilkS")
        (effects (font (size 0.7 0.7) (thickness 0.15)) (justify left bottom mirror))
    )
    (fp_text value "C_22u_100V_2220" (at -9.416 -2.833 90) (layer "B.Fab")
        (effects (font (size 0.7 0.7) (thickness 0.15)) (justify left bottom mirror))
    )
    (fp_text user "License: Apache-2.0" (at -3.7 -6.9 90) (layer "B.Fab") hide
        (effects (font (size 0.7 0.7) (thickness 0.15)) (justify left bottom mirror))
    )
    (fp_text user "${REFERENCE}" (at -3.7 -5.9 90) (layer "B.Fab") hide
        (effects (font (size 0.7 0.7) (thickness 0.15)) (justify left bottom mirror))
    )
    (fp_text user "Author: Antmicro" (at -3.7 -7.9 90) (layer "B.Fab") hide
        (effects (font (size 0.7 0.7) (thickness 0.15)) (justify left bottom mirror))
    )
    (fp_line (start -1.415 -2.61) (end 1.415 -2.61)
      (stroke (width 0.15) (type solid)) (layer "B.SilkS"))
    (fp_line (start -1.415 2.61) (end 1.415 2.61)
      (stroke (width 0.15) (type solid)) (layer "B.SilkS"))
    (fp_rect (start -3.7 2.95) (end 3.7 -2.95)
      (stroke (width 0.05) (type solid)) (fill none) (layer "B.CrtYd"))
    (fp_rect (start -2.85 2.5) (end 2.85 -2.5)
      (stroke (width 0.15) (type solid)) (fill none) (layer "B.Fab"))
    (pad "1" smd roundrect (at -2.55 0 270) (size 1.8 5.4) (layers "B.Cu" "B.Paste" "B.Mask") (roundrect_rratio 0.138889)
      (net 4 "GNDD") (pintype "passive"))
    (pad "2" smd roundrect (at 2.55 0 270) (size 1.8 5.4) (layers "B.Cu" "B.Paste" "B.Mask") (roundrect_rratio 0.138889)
      (net 6 "/PoE/VDD_POE_IN") (pintype "passive"))
  )
	(footprint "scalenode-cm4-baseboard-footprints:FB_0805_2012Metric" (layer "B.Cu")
    (at 85.2 95.3)
    (property "Author" "Antmicro")
    (property "License" "Apache-2.0")
    (property "MPN" "BLM21PG221SN1D")
    (property "Manufacturer" "Murata")
    (property "Sheetfile" "poe.kicad_sch")
    (property "Sheetname" "PoE")
    (attr smd)
    (fp_text reference "FB2" (at -1.75 0.5 180) (layer "B.SilkS")
        (effects (font (size 0.7 0.7) (thickness 0.15)) (justify left bottom mirror))
    )
    (fp_text value "FB_220Z_2A_Murata-BLM21PG_0805" (at 0 -1.8 180) (layer "B.Fab")
        (effects (font (size 0.7 0.7) (thickness 0.15)) (justify left bottom mirror))
    )
    (fp_text user "License: Apache-2.0" (at -1.9 -5.75 180) (layer "B.Fab") hide
        (effects (font (size 0.7 0.7) (thickness 0.15)) (justify left bottom mirror))
    )
    (fp_text user "Author: Antmicro" (at -1.9 -4.4 180) (layer "B.Fab") hide
        (effects (font (size 0.7 0.7) (thickness 0.15)) (justify left bottom mirror))
    )
    (fp_text user "${REFERENCE}" (at -1.9 -3.1 180) (layer "B.Fab") hide
        (effects (font (size 0.7 0.7) (thickness 0.15)) (justify left bottom mirror))
    )
    (fp_line (start -0.32 -0.699) (end 0.28 -0.699)
      (stroke (width 0.15) (type solid)) (layer "B.SilkS"))
    (fp_line (start -0.3 0.701) (end 0.298 0.701)
      (stroke (width 0.15) (type solid)) (layer "B.SilkS"))
    (fp_rect (start -1.75 0.85) (end 1.75 -0.85)
      (stroke (width 0.05) (type solid)) (fill none) (layer "B.CrtYd"))
    (fp_line (start -0.951 -0.68) (end 0.949 -0.68)
      (stroke (width 0.15) (type solid)) (layer "B.Fab"))
    (fp_line (start -0.951 0.677) (end -0.951 -0.675)
      (stroke (width 0.15) (type solid)) (layer "B.Fab"))
    (fp_line (start -0.951 0.682) (end 0.949 0.682)
      (stroke (width 0.15) (type solid)) (layer "B.Fab"))
    (fp_line (start 0.949 0.677) (end 0.949 -0.675)
      (stroke (width 0.15) (type solid)) (layer "B.Fab"))
    (pad "1" smd roundrect (at -1.1 0.001) (size 1 1.4) (layers "B.Cu" "B.Paste" "B.Mask") (roundrect_rratio 0.15)
      (net 191 "Net-(D4-Pad1)") (pintype "passive"))
    (pad "2" smd roundrect (at 1.1 0.001) (size 1 1.4) (layers "B.Cu" "B.Paste" "B.Mask") (roundrect_rratio 0.15)
      (net 6 "/PoE/VDD_POE_IN") (pintype "passive"))
  )
	(footprint "scalenode-cm4-baseboard-footprints:SOIC-4_W3.9mm" (layer "B.Cu")
    (at 98.455 65.746 90)
    (property "Author" "Antmicro")
    (property "License" "Apache-2.0")
    (property "MPN" "MB10S")
    (property "Manufacturer" "Multicomp Pro")
    (property "Sheetfile" "poe.kicad_sch")
    (property "Sheetname" "PoE")
    (property "ki_description" "Bridge Rectifier")
    (attr smd)
    (fp_text reference "D5" (at 0.546 -2.88 270) (layer "B.SilkS")
        (effects (font (size 0.7 0.7) (thickness 0.15)) (justify left bottom mirror))
    )
    (fp_text value "MB10S" (at 0 -3.6 270) (layer "B.Fab")
        (effects (font (size 0.7 0.7) (thickness 0.15)) (justify left bottom mirror))
    )
    (fp_text user "${REFERENCE}" (at -4.111 -5.347 270) (layer "B.Fab") hide
        (effects (font (size 0.7 0.7) (thickness 0.15)) (justify left bottom mirror))
    )
    (fp_text user "Author: Antmicro" (at -4.111 -6.546 270) (layer "B.Fab") hide
        (effects (font (size 0.7 0.7) (thickness 0.15)) (justify left bottom mirror))
    )
    (fp_text user "License: Apache-2.0" (at -4.111 -7.746 270) (layer "B.Fab") hide
        (effects (font (size 0.7 0.7) (thickness 0.15)) (justify left bottom mirror))
    )
    (fp_line (start -3.9 2.48) (end 2.1 2.48)
      (stroke (width 0.15) (type solid)) (layer "B.SilkS"))
    (fp_line (start -2.101 -2.479) (end 2.1 -2.479)
      (stroke (width 0.15) (type solid)) (layer "B.SilkS"))
    (fp_circle (center -3.301 3.101) (end -3.202 3.101)
      (stroke (width 0.15) (type solid)) (fill solid) (layer "B.SilkS"))
    (fp_line (start -4.13 -2.72) (end 4.11 -2.72)
      (stroke (width 0.05) (type solid)) (layer "B.CrtYd"))
    (fp_line (start -4.13 2.73) (end -4.13 -2.72)
      (stroke (width 0.05) (type solid)) (layer "B.CrtYd"))
    (fp_line (start 4.11 -2.72) (end 4.11 2.73)
      (stroke (width 0.05) (type solid)) (layer "B.CrtYd"))
    (fp_line (start 4.11 2.73) (end -4.13 2.73)
      (stroke (width 0.05) (type solid)) (layer "B.CrtYd"))
    (fp_line (start -2.101 -2.479) (end -2.101 2.48)
      (stroke (width 0.15) (type solid)) (layer "B.Fab"))
    (fp_line (start -2.101 2.48) (end 2.1 2.48)
      (stroke (width 0.15) (type solid)) (layer "B.Fab"))
    (fp_line (start 2.1 -2.479) (end -2.101 -2.479)
      (stroke (width 0.15) (type solid)) (layer "B.Fab"))
    (fp_line (start 2.1 2.48) (end 2.1 -2.479)
      (stroke (width 0.15) (type solid)) (layer "B.Fab"))
    (pad "1" smd roundrect (at -2.851 1.226 90) (size 1.8 1) (layers "B.Cu" "B.Paste" "B.Mask") (roundrect_rratio 0.25)
      (net 191 "Net-(D4-Pad1)") (pinfunction "1") (pintype "passive"))
    (pad "2" smd roundrect (at -2.851 -1.225 90) (size 1.8 1) (layers "B.Cu" "B.Paste" "B.Mask") (roundrect_rratio 0.25)
      (net 231 "Net-(D4-Pad2)") (pinfunction "2") (pintype "passive"))
    (pad "3" smd roundrect (at 2.85 -1.225 90) (size 1.8 1) (layers "B.Cu" "B.Paste" "B.Mask") (roundrect_rratio 0.25)
      (net 3 "/PoE/PAIR45") (pinfunction "3") (pintype "passive"))
    (pad "4" smd roundrect (at 2.85 1.226 90) (size 1.8 1) (layers "B.Cu" "B.Paste" "B.Mask") (roundrect_rratio 0.25)
      (net 20 "/PoE/PAIR78") (pinfunction "4") (pintype "passive"))
  )
	(footprint "scalenode-cm4-baseboard-footprints:FB_0805_2012Metric" (layer "B.Cu")
    (at 86.1 92.5)
    (property "Author" "Antmicro")
    (property "License" "Apache-2.0")
    (property "MPN" "BLM21PG221SN1D")
    (property "Manufacturer" "Murata")
    (property "Sheetfile" "poe.kicad_sch")
    (property "Sheetname" "PoE")
    (attr smd)
    (fp_text reference "FB1" (at -1.75 0.325 180) (layer "B.SilkS")
        (effects (font (size 0.7 0.7) (thickness 0.15)) (justify left bottom mirror))
    )
    (fp_text value "FB_220Z_2A_Murata-BLM21PG_0805" (at 0 -1.8 180) (layer "B.Fab")
        (effects (font (size 0.7 0.7) (thickness 0.15)) (justify left bottom mirror))
    )
    (fp_text user "${REFERENCE}" (at -1.9 -3.1 180) (layer "B.Fab") hide
        (effects (font (size 0.7 0.7) (thickness 0.15)) (justify left bottom mirror))
    )
    (fp_text user "Author: Antmicro" (at -1.9 -4.4 180) (layer "B.Fab") hide
        (effects (font (size 0.7 0.7) (thickness 0.15)) (justify left bottom mirror))
    )
    (fp_text user "License: Apache-2.0" (at -1.9 -5.75 180) (layer "B.Fab") hide
        (effects (font (size 0.7 0.7) (thickness 0.15)) (justify left bottom mirror))
    )
    (fp_line (start -0.32 -0.699) (end 0.28 -0.699)
      (stroke (width 0.15) (type solid)) (layer "B.SilkS"))
    (fp_line (start -0.3 0.701) (end 0.298 0.701)
      (stroke (width 0.15) (type solid)) (layer "B.SilkS"))
    (fp_rect (start -1.75 0.85) (end 1.75 -0.85)
      (stroke (width 0.05) (type solid)) (fill none) (layer "B.CrtYd"))
    (fp_line (start -0.951 -0.68) (end 0.949 -0.68)
      (stroke (width 0.15) (type solid)) (layer "B.Fab"))
    (fp_line (start -0.951 0.677) (end -0.951 -0.675)
      (stroke (width 0.15) (type solid)) (layer "B.Fab"))
    (fp_line (start -0.951 0.682) (end 0.949 0.682)
      (stroke (width 0.15) (type solid)) (layer "B.Fab"))
    (fp_line (start 0.949 0.677) (end 0.949 -0.675)
      (stroke (width 0.15) (type solid)) (layer "B.Fab"))
    (pad "1" smd roundrect (at -1.1 0.001) (size 1 1.4) (layers "B.Cu" "B.Paste" "B.Mask") (roundrect_rratio 0.15)
      (net 231 "Net-(D4-Pad2)") (pintype "passive"))
    (pad "2" smd roundrect (at 1.1 0.001) (size 1 1.4) (layers "B.Cu" "B.Paste" "B.Mask") (roundrect_rratio 0.15)
      (net 5 "VSS") (pintype "passive"))
  )
	(footprint "scalenode-cm4-baseboard-footprints:SOIC-4_W3.9mm" (layer "B.Cu")
    (at 97.47 77.136 -90)
    (property "Author" "Antmicro")
    (property "License" "Apache-2.0")
    (property "MPN" "MB10S")
    (property "Manufacturer" "Multicomp Pro")
    (property "Sheetfile" "poe.kicad_sch")
    (property "Sheetname" "PoE")
    (property "ki_description" "Bridge Rectifier")
    (attr smd)
    (fp_text reference "D4" (at 0 2.9 90) (layer "B.SilkS")
        (effects (font (size 0.7 0.7) (thickness 0.15)) (justify left bottom mirror))
    )
    (fp_text value "MB10S" (at 0 -3.6 90) (layer "B.Fab")
        (effects (font (size 0.7 0.7) (thickness 0.15)) (justify left bottom mirror))
    )
    (fp_text user "License: Apache-2.0" (at -4.111 -7.746 90) (layer "B.Fab") hide
        (effects (font (size 0.7 0.7) (thickness 0.15)) (justify left bottom mirror))
    )
    (fp_text user "${REFERENCE}" (at -4.111 -5.347 90) (layer "B.Fab") hide
        (effects (font (size 0.7 0.7) (thickness 0.15)) (justify left bottom mirror))
    )
    (fp_text user "Author: Antmicro" (at -4.111 -6.546 90) (layer "B.Fab") hide
        (effects (font (size 0.7 0.7) (thickness 0.15)) (justify left bottom mirror))
    )
    (fp_line (start -3.9 2.48) (end 2.1 2.48)
      (stroke (width 0.15) (type solid)) (layer "B.SilkS"))
    (fp_line (start -2.101 -2.479) (end 2.1 -2.479)
      (stroke (width 0.15) (type solid)) (layer "B.SilkS"))
    (fp_circle (center -3.301 3.101) (end -3.202 3.101)
      (stroke (width 0.15) (type solid)) (fill solid) (layer "B.SilkS"))
    (fp_line (start -4.13 -2.72) (end 4.11 -2.72)
      (stroke (width 0.05) (type solid)) (layer "B.CrtYd"))
    (fp_line (start -4.13 2.73) (end -4.13 -2.72)
      (stroke (width 0.05) (type solid)) (layer "B.CrtYd"))
    (fp_line (start 4.11 -2.72) (end 4.11 2.73)
      (stroke (width 0.05) (type solid)) (layer "B.CrtYd"))
    (fp_line (start 4.11 2.73) (end -4.13 2.73)
      (stroke (width 0.05) (type solid)) (layer "B.CrtYd"))
    (fp_line (start -2.101 -2.479) (end -2.101 2.48)
      (stroke (width 0.15) (type solid)) (layer "B.Fab"))
    (fp_line (start -2.101 2.48) (end 2.1 2.48)
      (stroke (width 0.15) (type solid)) (layer "B.Fab"))
    (fp_line (start 2.1 -2.479) (end -2.101 -2.479)
      (stroke (width 0.15) (type solid)) (layer "B.Fab"))
    (fp_line (start 2.1 2.48) (end 2.1 -2.479)
      (stroke (width 0.15) (type solid)) (layer "B.Fab"))
    (pad "1" smd roundrect (at -2.851 1.226 270) (size 1.8 1) (layers "B.Cu" "B.Paste" "B.Mask") (roundrect_rratio 0.25)
      (net 191 "Net-(D4-Pad1)") (pinfunction "1") (pintype "passive"))
    (pad "2" smd roundrect (at -2.851 -1.225 270) (size 1.8 1) (layers "B.Cu" "B.Paste" "B.Mask") (roundrect_rratio 0.25)
      (net 231 "Net-(D4-Pad2)") (pinfunction "2") (pintype "passive"))
    (pad "3" smd roundrect (at 2.85 -1.225 270) (size 1.8 1) (layers "B.Cu" "B.Paste" "B.Mask") (roundrect_rratio 0.25)
      (net 1 "/PoE/PAIR12") (pinfunction "3") (pintype "passive"))
    (pad "4" smd roundrect (at 2.85 1.226 270) (size 1.8 1) (layers "B.Cu" "B.Paste" "B.Mask") (roundrect_rratio 0.25)
      (net 2 "/PoE/PAIR36") (pinfunction "4") (pintype "passive"))
  )
	(footprint "scalenode-cm4-baseboard-footprints:R_0603_1608Metric" (layer "B.Cu")
    (at 174.546 70.146 -90)
    (descr "Resistor SMD 0603")
    (tags "resistor SMD 0603")
    (property "Author" "Antmicro")
    (property "License" "Apache-2.0")
    (property "MPN" "CR0603-FX-1002ELF")
    (property "Manufacturer" "Bourns")
    (property "Sheetfile" "nvme-ssd.kicad_sch")
    (property "Sheetname" "NVMe SSD")
    (property "Tolerance" "1%")
    (property "Val" "10k")
    (property "ki_description" "10k resistor in 0603 package with 1% tolerance")
    (attr smd)
    (fp_text reference "R4" (at 1.368385 -0.404591 90) (layer "B.SilkS")
        (effects (font (size 0.7 0.7) (thickness 0.15)) (justify left bottom mirror))
    )
    (fp_text value "R_10k_0603" (at 0 -1.6 90) (layer "B.Fab")
        (effects (font (size 0.7 0.7) (thickness 0.15)) (justify left bottom mirror))
    )
    (fp_text user "License: Apache-2.0" (at -1.25 -5.9 90) (layer "B.Fab") hide
        (effects (font (size 0.7 0.7) (thickness 0.15)) (justify left bottom mirror))
    )
    (fp_text user "Author: Antmicro" (at -1.25 -4.9 90) (layer "B.Fab") hide
        (effects (font (size 0.7 0.7) (thickness 0.15)) (justify left bottom mirror))
    )
    (fp_text user "${REFERENCE}" (at -1.25 -3.898 90) (layer "B.Fab") hide
        (effects (font (size 0.7 0.7) (thickness 0.15)) (justify left bottom mirror))
    )
    (fp_line (start -0.3 -0.3) (end 0.3 -0.3)
      (stroke (width 0.15) (type solid)) (layer "B.SilkS"))
    (fp_line (start -0.3 0.3) (end 0.3 0.3)
      (stroke (width 0.15) (type solid)) (layer "B.SilkS"))
    (fp_rect (start -1.25 0.7) (end 1.25 -0.7)
      (stroke (width 0.05) (type solid)) (fill none) (layer "B.CrtYd"))
    (fp_rect (start -0.8 0.4) (end 0.8 -0.4)
      (stroke (width 0.15) (type solid)) (fill none) (layer "B.Fab"))
    (pad "1" smd roundrect (at -0.7 0 270) (size 0.6 0.8) (layers "B.Cu" "B.Paste" "B.Mask") (roundrect_rratio 0.2)
      (net 170 "3V3_SSD") (pintype "passive"))
    (pad "2" smd roundrect (at 0.7 0 270) (size 0.6 0.8) (layers "B.Cu" "B.Paste" "B.Mask") (roundrect_rratio 0.2)
      (net 99 "PSCIE_nRST") (pintype "passive"))
  )
	(footprint "scalenode-cm4-baseboard-footprints:R_0402_1005Metric" (layer "B.Cu")
    (at 102.8 70.906)
    (descr "Resistor SMD 0402")
    (tags "resistor SMD 0402")
    (property "Author" "Antmicro")
    (property "License" "Apache-2.0")
    (property "MPN" "CR0402-FX-75R0GLF")
    (property "Manufacturer" "Bourns")
    (property "Sheetfile" "poe.kicad_sch")
    (property "Sheetname" "PoE")
    (property "Tolerance" "1%")
    (property "Val" "75R")
    (property "ki_description" "75R resistor in 0402 package with 1% tolerance")
    (attr smd)
    (fp_text reference "R26" (at 3.075 0.369 180) (layer "B.SilkS")
        (effects (font (size 0.7 0.7) (thickness 0.15)) (justify left bottom mirror))
    )
    (fp_text value "R_75R_0402" (at 0 -1.4 180) (layer "B.Fab")
        (effects (font (size 0.7 0.7) (thickness 0.15)) (justify left bottom mirror))
    )
    (fp_text user "Author: Antmicro" (at -0.95 -4.169 180) (layer "B.Fab") hide
        (effects (font (size 0.7 0.7) (thickness 0.15)) (justify left bottom mirror))
    )
    (fp_text user "${REFERENCE}" (at -0.95 -3.168 180) (layer "B.Fab") hide
        (effects (font (size 0.7 0.7) (thickness 0.15)) (justify left bottom mirror))
    )
    (fp_text user "License: Apache-2.0" (at -0.95 -5.169 180) (layer "B.Fab") hide
        (effects (font (size 0.7 0.7) (thickness 0.15)) (justify left bottom mirror))
    )
    (fp_rect (start -0.95 0.48) (end 0.95 -0.48)
      (stroke (width 0.05) (type solid)) (fill none) (layer "B.CrtYd"))
    (fp_rect (start -0.5 0.25) (end 0.5 -0.25)
      (stroke (width 0.15) (type solid)) (fill none) (layer "B.Fab"))
    (pad "1" smd roundrect (at -0.485 0) (size 0.59 0.64) (layers "B.Cu" "B.Paste" "B.Mask") (roundrect_rratio 0.25)
      (net 9 "Net-(C30-Pad1)") (pintype "passive"))
    (pad "2" smd roundrect (at 0.485 0) (size 0.59 0.64) (layers "B.Cu" "B.Paste" "B.Mask") (roundrect_rratio 0.25)
      (net 8 "Net-(C31-Pad1)") (pintype "passive"))
  )
)
